# T6G (Grand Teton) — schematic netlist excerpt (pin names and nets, part order shuffled) for the footprints in the layout excerpt that follows; sources: Cadence DE-HDL packaged netlist, KiCad conversion of 04192023_DAF0TMB3IC0_F0TG_MB_C_brd_V02_OCP.brd

PC398_1  Q_CAP  22UF 4V 20% X6S  pkg C0805  page 218 : A = PVDDCR_CPU1_P1 ; B = GND
R1197  Q_RES  0 5% EMPTY  pkg 0402LF  page 153 : A = ESPI_CPU0_ALERT_P0_N ; B = ESPI_CPU0_ALERT_N
R206  Q_RES  0 5% CHIP  pkg 0402LF  page 160 : A = SMB_CPU0_CPU1_APML_BUF2_SDA_R1 ; B = SMB_CPU0_CPU1_APML_BUF2_SDA_R2

(kicad_pcb
	(version 20260206)
	(generator "pcbnew")
	(generator_version "10.0")
	(general
		(thickness 1.6)
		(legacy_teardrops no)
	)
	(paper "A4")
	(title_block
		(title "04192023_DAF0TMB3IC0_F0TG_MB_C_brd_V02_OCP.brd")
		(comment 1 "Grand Teton / footprints 8014-8016 of 8354")
	)
	(layers
		(0 "F.Cu" signal "TOP")
		(4 "In1.Cu" signal "GND")
		(6 "In2.Cu" signal "IN1")
		(8 "In3.Cu" signal "GND1")
		(10 "In4.Cu" signal "IN2")
		(12 "In5.Cu" signal "GND2")
		(14 "In6.Cu" signal "IN3")
		(16 "In7.Cu" signal "GND3")
		(18 "In8.Cu" signal "VCC")
		(20 "In9.Cu" signal "VCC1")
		(22 "In10.Cu" signal "GND4")
		(24 "In11.Cu" signal "IN4")
		(26 "In12.Cu" signal "GND5")
		(28 "In13.Cu" signal "IN5")
		(30 "In14.Cu" signal "GND6")
		(32 "In15.Cu" signal "IN6")
		(34 "In16.Cu" signal "GND7")
		(2 "B.Cu" signal "BOTTOM")
		(9 "F.Adhes" user "F.Adhesive")
		(11 "B.Adhes" user "B.Adhesive")
		(13 "F.Paste" user "Package Geometry/Pastemask Top")
		(15 "B.Paste" user "Package Geometry/Pastemask Bottom")
		(5 "F.SilkS" user "Ref Des/Silkscreen Top")
		(7 "B.SilkS" user "Ref Des/Silkscreen Bottom")
		(1 "F.Mask" user "Board Geometry/Soldermask Top")
		(3 "B.Mask" user "Board Geometry/Soldermask Bottom")
		(17 "Dwgs.User" user "User.Drawings")
		(19 "Cmts.User" user "User.Comments")
		(21 "Eco1.User" user "User.Eco1")
		(23 "Eco2.User" user "User.Eco2")
		(25 "Edge.Cuts" user "Board Geometry/Outline")
		(27 "Margin" user)
		(31 "F.CrtYd" user "Package Geometry/Place Bound Top")
		(29 "B.CrtYd" user "Package Geometry/Place Bound Bottom")
		(35 "F.Fab" user "Ref Des/Assembly Top")
		(33 "B.Fab" user "Ref Des/Assembly Bottom")
	)
	(footprint ""
		(layer "B.Cu")
		(at 81.522316 -326.312276 -90)
		(property "Reference" "PC398_1"
			(at 0 0 90)
			(layer "B.SilkS")
			(hide yes)
			(effects
				(font
					(size 1.27 1.27)
				)
				(justify mirror)
			)
		)
		(property "Value" ""
			(at 0 0 90)
			(layer "B.Fab")
			(effects
				(font
					(size 1.27 1.27)
				)
				(justify mirror)
			)
		)
		(duplicate_pad_numbers_are_jumpers no)
		(fp_line
			(start -1.524 0.762)
			(end 1.524 0.762)
			(stroke
				(width 0.1524)
				(type default)
			)
			(layer "B.SilkS")
		)
		(fp_line
			(start 1.524 0.762)
			(end 1.524 -0.762)
			(stroke
				(width 0.1524)
				(type default)
			)
			(layer "B.SilkS")
		)
		(fp_line
			(start -1.524 -0.762)
			(end -1.524 0.762)
			(stroke
				(width 0.1524)
				(type default)
			)
			(layer "B.SilkS")
		)
		(fp_line
			(start 1.524 -0.762)
			(end -1.524 -0.762)
			(stroke
				(width 0.1524)
				(type default)
			)
			(layer "B.SilkS")
		)
		(fp_line
			(start -1.1049 0.724916)
			(end -1.1049 -0.724916)
			(stroke
				(width 0.1)
				(type default)
			)
			(layer "B.Fab")
		)
		(fp_line
			(start 1.1049 0.724916)
			(end -1.1049 0.724916)
			(stroke
				(width 0.1)
				(type default)
			)
			(layer "B.Fab")
		)
		(fp_line
			(start -1.1049 -0.724916)
			(end 1.1049 -0.724916)
			(stroke
				(width 0.1)
				(type default)
			)
			(layer "B.Fab")
		)
		(fp_line
			(start 1.1049 -0.724916)
			(end 1.1049 0.724916)
			(stroke
				(width 0.1)
				(type default)
			)
			(layer "B.Fab")
		)
		(pad "1" smd rect
			(at 0.889 0 270)
			(size 1.016 1.27)
			(layers "B.Cu" "B.Mask" "B.Paste")
			(net "PVDDCR_CPU1_P1")
		)
		(pad "2" smd rect
			(at -0.889 0 270)
			(size 1.016 1.27)
			(layers "B.Cu" "B.Mask" "B.Paste")
			(net "GND")
		)
	)
	(footprint ""
		(layer "B.Cu")
		(at 229.997 -218.059 90)
		(property "Reference" "R206"
			(at 0 0 90)
			(layer "B.SilkS")
			(hide yes)
			(effects
				(font
					(size 1.27 1.27)
				)
				(justify mirror)
			)
		)
		(property "Value" ""
			(at 0 0 90)
			(layer "B.Fab")
			(effects
				(font
					(size 1.27 1.27)
				)
				(justify mirror)
			)
		)
		(duplicate_pad_numbers_are_jumpers no)
		(fp_line
			(start 0.7874 -0.4064)
			(end -0.7874 -0.4064)
			(stroke
				(width 0.1524)
				(type default)
			)
			(layer "B.SilkS")
		)
		(fp_line
			(start -0.7874 -0.4064)
			(end -0.7874 0.4064)
			(stroke
				(width 0.1524)
				(type default)
			)
			(layer "B.SilkS")
		)
		(fp_line
			(start 0.7874 0.4064)
			(end 0.7874 -0.4064)
			(stroke
				(width 0.1524)
				(type default)
			)
			(layer "B.SilkS")
		)
		(fp_line
			(start -0.7874 0.4064)
			(end 0.7874 0.4064)
			(stroke
				(width 0.1524)
				(type default)
			)
			(layer "B.SilkS")
		)
		(fp_line
			(start 0.67945 -0.305054)
			(end 0.12065 -0.305054)
			(stroke
				(width 0.1)
				(type default)
			)
			(layer "B.Fab")
		)
		(fp_line
			(start 0.12065 -0.305054)
			(end 0.12065 -0.2794)
			(stroke
				(width 0.1)
				(type default)
			)
			(layer "B.Fab")
		)
		(fp_line
			(start -0.12065 -0.3048)
			(end -0.67945 -0.3048)
			(stroke
				(width 0.1)
				(type default)
			)
			(layer "B.Fab")
		)
		(fp_line
			(start -0.67945 -0.3048)
			(end -0.67945 0.3048)
			(stroke
				(width 0.1)
				(type default)
			)
			(layer "B.Fab")
		)
		(fp_line
			(start 0.12065 -0.2794)
			(end -0.12065 -0.2794)
			(stroke
				(width 0.1)
				(type default)
			)
			(layer "B.Fab")
		)
		(fp_line
			(start -0.12065 -0.2794)
			(end -0.12065 -0.3048)
			(stroke
				(width 0.1)
				(type default)
			)
			(layer "B.Fab")
		)
		(fp_line
			(start 0.12065 0.2794)
			(end 0.12065 0.3048)
			(stroke
				(width 0.1)
				(type default)
			)
			(layer "B.Fab")
		)
		(fp_line
			(start -0.120396 0.2794)
			(end 0.12065 0.2794)
			(stroke
				(width 0.1)
				(type default)
			)
			(layer "B.Fab")
		)
		(fp_line
			(start 0.67945 0.3048)
			(end 0.67945 -0.305054)
			(stroke
				(width 0.1)
				(type default)
			)
			(layer "B.Fab")
		)
		(fp_line
			(start 0.12065 0.3048)
			(end 0.67945 0.3048)
			(stroke
				(width 0.1)
				(type default)
			)
			(layer "B.Fab")
		)
		(fp_line
			(start -0.120396 0.3048)
			(end -0.120396 0.2794)
			(stroke
				(width 0.1)
				(type default)
			)
			(layer "B.Fab")
		)
		(fp_line
			(start -0.67945 0.3048)
			(end -0.120396 0.3048)
			(stroke
				(width 0.1)
				(type default)
			)
			(layer "B.Fab")
		)
		(pad "1" smd circle
			(at 0.40005 0 270)
			(size 0 0)
			(layers "B.Cu" "B.Mask" "B.Paste")
			(net "SMB_CPU0_CPU1_APML_BUF2_SDA_R1")
		)
		(pad "2" smd circle
			(at -0.40005 0 270)
			(size 0 0)
			(layers "B.Cu" "B.Mask" "B.Paste")
			(net "SMB_CPU0_CPU1_APML_BUF2_SDA_R2")
		)
	)
	(footprint ""
		(layer "B.Cu")
		(at 188.101224 -145.585434 180)
		(property "Reference" "R1197"
			(at 0 0 0)
			(layer "B.SilkS")
			(hide yes)
			(effects
				(font
					(size 1.27 1.27)
				)
				(justify mirror)
			)
		)
		(property "Value" ""
			(at 0 0 0)
			(layer "B.Fab")
			(effects
				(font
					(size 1.27 1.27)
				)
				(justify mirror)
			)
		)
		(duplicate_pad_numbers_are_jumpers no)
		(fp_line
			(start 0.7874 0.4064)
			(end 0.7874 -0.4064)
			(stroke
				(width 0.1524)
				(type default)
			)
			(layer "B.SilkS")
		)
		(fp_line
			(start 0.7874 -0.4064)
			(end -0.7874 -0.4064)
			(stroke
				(width 0.1524)
				(type default)
			)
			(layer "B.SilkS")
		)
		(fp_line
			(start -0.7874 0.4064)
			(end 0.7874 0.4064)
			(stroke
				(width 0.1524)
				(type default)
			)
			(layer "B.SilkS")
		)
		(fp_line
			(start -0.7874 -0.4064)
			(end -0.7874 0.4064)
			(stroke
				(width 0.1524)
				(type default)
			)
			(layer "B.SilkS")
		)
		(fp_line
			(start 0.67945 0.3048)
			(end 0.67945 -0.305054)
			(stroke
				(width 0.1)
				(type default)
			)
			(layer "B.Fab")
		)
		(fp_line
			(start 0.67945 -0.305054)
			(end 0.12065 -0.305054)
			(stroke
				(width 0.1)
				(type default)
			)
			(layer "B.Fab")
		)
		(fp_line
			(start 0.12065 0.3048)
			(end 0.67945 0.3048)
			(stroke
				(width 0.1)
				(type default)
			)
			(layer "B.Fab")
		)
		(fp_line
			(start 0.12065 0.2794)
			(end 0.12065 0.3048)
			(stroke
				(width 0.1)
				(type default)
			)
			(layer "B.Fab")
		)
		(fp_line
			(start 0.12065 -0.2794)
			(end -0.12065 -0.2794)
			(stroke
				(width 0.1)
				(type default)
			)
			(layer "B.Fab")
		)
		(fp_line
			(start 0.12065 -0.305054)
			(end 0.12065 -0.2794)
			(stroke
				(width 0.1)
				(type default)
			)
			(layer "B.Fab")
		)
		(fp_line
			(start -0.120396 0.3048)
			(end -0.120396 0.2794)
			(stroke
				(width 0.1)
				(type default)
			)
			(layer "B.Fab")
		)
		(fp_line
			(start -0.120396 0.2794)
			(end 0.12065 0.2794)
			(stroke
				(width 0.1)
				(type default)
			)
			(layer "B.Fab")
		)
		(fp_line
			(start -0.12065 -0.2794)
			(end -0.12065 -0.3048)
			(stroke
				(width 0.1)
				(type default)
			)
			(layer "B.Fab")
		)
		(fp_line
			(start -0.12065 -0.3048)
			(end -0.67945 -0.3048)
			(stroke
				(width 0.1)
				(type default)
			)
			(layer "B.Fab")
		)
		(fp_line
			(start -0.67945 0.3048)
			(end -0.120396 0.3048)
			(stroke
				(width 0.1)
				(type default)
			)
			(layer "B.Fab")
		)
		(fp_line
			(start -0.67945 -0.3048)
			(end -0.67945 0.3048)
			(stroke
				(width 0.1)
				(type default)
			)
			(layer "B.Fab")
		)
		(pad "1" smd circle
			(at 0.40005 0)
			(size 0 0)
			(layers "B.Cu" "B.Mask" "B.Paste")
			(net "ESPI_CPU0_ALERT_P0_N")
		)
		(pad "2" smd circle
			(at -0.40005 0)
			(size 0 0)
			(layers "B.Cu" "B.Mask" "B.Paste")
			(net "ESPI_CPU0_ALERT_N")
		)
	)
)
